(kicad_pcb
	(version 20260206)
	(generator "pcbnew")
	(generator_version "10.0")
	(general
		(thickness 1.6)
		(legacy_teardrops no)
	)
	(paper "A4")
	(title_block
		(title "v1-chassis-manager — T6M_CM_d_v01_1031_1645.brd")
		(comment 1 "Open CloudServer (Microsoft) / footprints 874-876 of 2512")
	)
	(layers
		(0 "F.Cu" signal "TOP")
		(4 "In1.Cu" signal "GND1")
		(6 "In2.Cu" signal "IN1")
		(8 "In3.Cu" signal "VCC1")
		(10 "In4.Cu" signal "VCC2")
		(12 "In5.Cu" signal "GND2")
		(14 "In6.Cu" signal "IN2")
		(16 "In7.Cu" signal "IN3")
		(18 "In8.Cu" signal "GND3")
		(2 "B.Cu" signal "BOTTOM")
		(9 "F.Adhes" user "F.Adhesive")
		(11 "B.Adhes" user "B.Adhesive")
		(13 "F.Paste" user "Package Geometry/Pastemask Top")
		(15 "B.Paste" user "Package Geometry/Pastemask Bottom")
		(5 "F.SilkS" user "Ref Des/Silkscreen Top")
		(7 "B.SilkS" user "Ref Des/Silkscreen Bottom")
		(1 "F.Mask" user "Board Geometry/Soldermask Top")
		(3 "B.Mask" user "Board Geometry/Soldermask Bottom")
		(17 "Dwgs.User" user "User.Drawings")
		(19 "Cmts.User" user "User.Comments")
		(21 "Eco1.User" user "User.Eco1")
		(23 "Eco2.User" user "User.Eco2")
		(25 "Edge.Cuts" user "Board Geometry/Outline")
		(27 "Margin" user)
		(31 "F.CrtYd" user "Package Geometry/Place Bound Top")
		(29 "B.CrtYd" user "Package Geometry/Place Bound Bottom")
		(35 "F.Fab" user "Ref Des/Assembly Top")
		(33 "B.Fab" user "Ref Des/Assembly Bottom")
	)
	(footprint ""
		(layer "F.Cu")
		(at 82.340196 -109.114082 180)
		(property "Reference" "C842"
			(at 5.505196 0.567944 0)
			(unlocked yes)
			(layer "F.SilkS")
			(effects
				(font
					(size 0.7874 0.5842)
					(thickness 0.1524)
				)
				(justify left)
			)
		)
		(property "Value" ""
			(at 0 0 180)
			(layer "F.Fab")
			(effects
				(font
					(size 1.27 1.27)
				)
			)
		)
		(duplicate_pad_numbers_are_jumpers no)
		(fp_line
			(start 0.7874 0.4064)
			(end -0.7874 0.4064)
			(stroke
				(width 0.1524)
				(type default)
			)
			(layer "F.SilkS")
		)
		(fp_line
			(start 0.7874 -0.4064)
			(end 0.7874 0.4064)
			(stroke
				(width 0.1524)
				(type default)
			)
			(layer "F.SilkS")
		)
		(fp_line
			(start 0 0.381)
			(end 0 -0.381)
			(stroke
				(width 0.1524)
				(type default)
			)
			(layer "F.SilkS")
		)
		(fp_line
			(start -0.7874 0.4064)
			(end -0.7874 -0.4064)
			(stroke
				(width 0.1524)
				(type default)
			)
			(layer "F.SilkS")
		)
		(fp_line
			(start -0.7874 -0.4064)
			(end 0.7874 -0.4064)
			(stroke
				(width 0.1524)
				(type default)
			)
			(layer "F.SilkS")
		)
		(fp_poly
			(pts
				(xy -0.5334 0.254) (xy -0.635 0.254) (xy -0.635 0.2286) (xy -0.635 -0.254) (xy -0.5334 -0.254) (xy -0.5334 -0.2794)
				(xy 0.5334 -0.2794) (xy 0.5334 -0.254) (xy 0.635 -0.254) (xy 0.635 0.254) (xy 0.5334 0.254) (xy 0.5334 0.2794)
				(xy -0.508 0.2794) (xy -0.5334 0.2794)
			)
			(stroke
				(width 0)
				(type default)
			)
			(fill no)
			(layer "F.CrtYd")
		)
		(pad "1" smd rect
			(at 0.40005 0 180)
			(size 0.4572 0.508)
			(layers "F.Cu" "F.Mask" "F.Paste")
			(net "FM_CPLD_NODE1_P3V3_SUS_EN")
		)
		(pad "2" smd rect
			(at -0.40005 0 180)
			(size 0.4572 0.508)
			(layers "F.Cu" "F.Mask" "F.Paste")
			(net "GND")
		)
	)
	(footprint ""
		(layer "F.Cu")
		(at 83.866228 -133.213094 -90)
		(property "Reference" "D33"
			(at 5.3213 2.668524 90)
			(unlocked yes)
			(layer "F.SilkS")
			(effects
				(font
					(size 0.7874 0.5842)
					(thickness 0.1524)
				)
				(justify left)
			)
		)
		(property "Value" ""
			(at 0 0 270)
			(layer "F.Fab")
			(effects
				(font
					(size 1.27 1.27)
				)
			)
		)
		(duplicate_pad_numbers_are_jumpers no)
		(fp_line
			(start -1.3208 0.5588)
			(end -1.3208 -0.5588)
			(stroke
				(width 0.1524)
				(type default)
			)
			(layer "F.SilkS")
		)
		(fp_line
			(start 1.3208 0.5588)
			(end -1.3208 0.5588)
			(stroke
				(width 0.1524)
				(type default)
			)
			(layer "F.SilkS")
		)
		(fp_line
			(start 1.6256 0.5588)
			(end 1.6256 -0.5588)
			(stroke
				(width 0.1524)
				(type default)
			)
			(layer "F.SilkS")
		)
		(fp_line
			(start 1.778 0.5588)
			(end 1.3208 0.5588)
			(stroke
				(width 0.1524)
				(type default)
			)
			(layer "F.SilkS")
		)
		(fp_line
			(start -1.3208 -0.5588)
			(end 1.3208 -0.5588)
			(stroke
				(width 0.1524)
				(type default)
			)
			(layer "F.SilkS")
		)
		(fp_line
			(start 1.3208 -0.5588)
			(end 1.3208 0.5588)
			(stroke
				(width 0.1524)
				(type default)
			)
			(layer "F.SilkS")
		)
		(fp_line
			(start 1.4732 -0.5588)
			(end 1.4732 0.5588)
			(stroke
				(width 0.1524)
				(type default)
			)
			(layer "F.SilkS")
		)
		(fp_line
			(start 1.778 -0.5588)
			(end 1.778 0.5588)
			(stroke
				(width 0.1524)
				(type default)
			)
			(layer "F.SilkS")
		)
		(fp_line
			(start 1.778 -0.5588)
			(end 1.3208 -0.5588)
			(stroke
				(width 0.1524)
				(type default)
			)
			(layer "F.SilkS")
		)
		(fp_circle
			(center 2.4384 0)
			(end 2.4384 -0.413512)
			(stroke
				(width 0.1524)
				(type default)
			)
			(fill no)
			(layer "F.SilkS")
		)
		(fp_rect
			(start -1.1684 0.508)
			(end 1.1684 -0.508)
			(stroke
				(width 0)
				(type default)
			)
			(fill no)
			(layer "F.CrtYd")
		)
		(fp_text user "-"
			(at 2.481834 0.54356 270)
			(unlocked yes)
			(layer "F.SilkS")
			(effects
				(font
					(size 0.7874 0.5842)
					(thickness 0.1524)
				)
				(justify left)
			)
		)
		(pad "A" smd rect
			(at -0.750062 0 270)
			(size 0.8128 0.8128)
			(layers "F.Cu" "F.Mask" "F.Paste")
			(net "P3V3_NODE1")
		)
		(pad "C" smd rect
			(at 0.750062 0 270)
			(size 0.8128 0.8128)
			(layers "F.Cu" "F.Mask" "F.Paste")
			(net "N53313479")
		)
	)
	(footprint ""
		(layer "F.Cu")
		(at 18.04924 -47.992284 180)
		(property "Reference" "R641"
			(at -12.91336 -4.116324 0)
			(unlocked yes)
			(layer "F.SilkS")
			(effects
				(font
					(size 0.7874 0.5842)
					(thickness 0.1524)
				)
				(justify left)
			)
		)
		(property "Value" ""
			(at 0 0 180)
			(layer "F.Fab")
			(effects
				(font
					(size 1.27 1.27)
				)
			)
		)
		(duplicate_pad_numbers_are_jumpers no)
		(fp_line
			(start 0.7874 0.4064)
			(end -0.7874 0.4064)
			(stroke
				(width 0.1524)
				(type default)
			)
			(layer "F.SilkS")
		)
		(fp_line
			(start 0.7874 -0.4064)
			(end 0.7874 0.4064)
			(stroke
				(width 0.1524)
				(type default)
			)
			(layer "F.SilkS")
		)
		(fp_line
			(start -0.7874 0.4064)
			(end -0.7874 -0.4064)
			(stroke
				(width 0.1524)
				(type default)
			)
			(layer "F.SilkS")
		)
		(fp_line
			(start -0.7874 -0.4064)
			(end 0.7874 -0.4064)
			(stroke
				(width 0.1524)
				(type default)
			)
			(layer "F.SilkS")
		)
		(fp_poly
			(pts
				(xy -0.508 0.2794) (xy -0.508 0.2286) (xy -0.635 0.2286) (xy -0.635 -0.254) (xy -0.5334 -0.254)
				(xy -0.5334 -0.2794) (xy 0.5334 -0.2794) (xy 0.5334 -0.254) (xy 0.635 -0.254) (xy 0.635 0.254) (xy 0.5334 0.254)
				(xy 0.5334 0.2794)
			)
			(stroke
				(width 0)
				(type default)
			)
			(fill no)
			(layer "F.CrtYd")
		)
		(pad "1" smd rect
			(at 0.40005 0 180)
			(size 0.4572 0.508)
			(layers "F.Cu" "F.Mask" "F.Paste")
			(net "CRT_G_L")
		)
		(pad "2" smd rect
			(at -0.40005 0 180)
			(size 0.4572 0.508)
			(layers "F.Cu" "F.Mask" "F.Paste")
			(net "GND")
		)
	)
)
